# S9S_MB_2U (Grand Teton) — schematic netlist excerpt (pin names and nets, part order shuffled) for the footprints in the layout excerpt that follows; sources: Cadence DE-HDL packaged netlist, KiCad conversion of 03242023_DA0F0TMBIJ0_F0T_Motherboard_J_brd_V01_OCP.brd

C729  Q_CAP_DIFFBUS  DIFF BUS_0.22UF 6.3V 20% X6S  pkg C0201  page 176 : \1\ = P5E_CPU1_PE0_TX_C_DP<6> ; \2\ = P5E_CPU1_PE0_TX_DP<6>
C1523  Q_CAP_DIFFBUS  DIFF BUS_0.22UF 6.3V 20% X6S  pkg C0201  page 177 : \1\ = P5E_CPU1_PE3_TX_C_DP<12> ; \2\ = P5E_CPU1_PE3_TX_DP<12>
H90  HOLE  EMPTY  pkg TH  page 311 : \1\ = NC
R4208  Q_RES  200K 1% EMPTY  pkg 0402LF  page 170 : A = P3V3_AUX ; B = FM_THERMAL_ALERT_N

(kicad_pcb
	(version 20260206)
	(generator "pcbnew")
	(generator_version "10.0")
	(general
		(thickness 1.6)
		(legacy_teardrops no)
	)
	(paper "A4")
	(title_block
		(title "03242023_DA0F0TMBIJ0_F0T_Motherboard_J_brd_V01_OCP.brd")
		(comment 1 "Grand Teton / footprints 3024-3027 of 6105")
	)
	(layers
		(0 "F.Cu" signal "TOP")
		(4 "In1.Cu" signal "GND")
		(6 "In2.Cu" signal "IN1")
		(8 "In3.Cu" signal "GND1")
		(10 "In4.Cu" signal "IN2")
		(12 "In5.Cu" signal "GND2")
		(14 "In6.Cu" signal "IN3")
		(16 "In7.Cu" signal "GND3")
		(18 "In8.Cu" signal "VCC")
		(20 "In9.Cu" signal "VCC1")
		(22 "In10.Cu" signal "GND4")
		(24 "In11.Cu" signal "IN4")
		(26 "In12.Cu" signal "GND5")
		(28 "In13.Cu" signal "IN5")
		(30 "In14.Cu" signal "GND6")
		(32 "In15.Cu" signal "IN6")
		(34 "In16.Cu" signal "GND7")
		(2 "B.Cu" signal "BOTTOM")
		(9 "F.Adhes" user "F.Adhesive")
		(11 "B.Adhes" user "B.Adhesive")
		(13 "F.Paste" user "Package Geometry/Pastemask Top")
		(15 "B.Paste" user "Package Geometry/Pastemask Bottom")
		(5 "F.SilkS" user "Ref Des/Silkscreen Top")
		(7 "B.SilkS" user "Ref Des/Silkscreen Bottom")
		(1 "F.Mask" user "Board Geometry/Soldermask Top")
		(3 "B.Mask" user "Board Geometry/Soldermask Bottom")
		(17 "Dwgs.User" user "User.Drawings")
		(19 "Cmts.User" user "User.Comments")
		(21 "Eco1.User" user "User.Eco1")
		(23 "Eco2.User" user "User.Eco2")
		(25 "Edge.Cuts" user "Board Geometry/Outline")
		(27 "Margin" user)
		(31 "F.CrtYd" user "Package Geometry/Place Bound Top")
		(29 "B.CrtYd" user "Package Geometry/Place Bound Bottom")
		(35 "F.Fab" user "Ref Des/Assembly Top")
		(33 "B.Fab" user "Ref Des/Assembly Bottom")
	)
	(footprint ""
		(layer "F.Cu")
		(at 367.920778 -417.15055 90)
		(property "Reference" "R4208"
			(at 0 0 90)
			(layer "F.SilkS")
			(hide yes)
			(effects
				(font
					(size 1.27 1.27)
				)
			)
		)
		(property "Value" ""
			(at 0 0 90)
			(layer "F.Fab")
			(effects
				(font
					(size 1.27 1.27)
				)
			)
		)
		(duplicate_pad_numbers_are_jumpers no)
		(fp_line
			(start 0.7874 -0.4064)
			(end 0.7874 0.4064)
			(stroke
				(width 0.1524)
				(type default)
			)
			(layer "F.SilkS")
		)
		(fp_line
			(start -0.7874 -0.4064)
			(end 0.7874 -0.4064)
			(stroke
				(width 0.1524)
				(type default)
			)
			(layer "F.SilkS")
		)
		(fp_line
			(start 0.7874 0.4064)
			(end -0.7874 0.4064)
			(stroke
				(width 0.1524)
				(type default)
			)
			(layer "F.SilkS")
		)
		(fp_line
			(start -0.7874 0.4064)
			(end -0.7874 -0.4064)
			(stroke
				(width 0.1524)
				(type default)
			)
			(layer "F.SilkS")
		)
		(fp_line
			(start -0.12065 -0.305054)
			(end -0.12065 -0.2794)
			(stroke
				(width 0.1)
				(type default)
			)
			(layer "F.Fab")
		)
		(fp_line
			(start -0.67945 -0.305054)
			(end -0.12065 -0.305054)
			(stroke
				(width 0.1)
				(type default)
			)
			(layer "F.Fab")
		)
		(fp_line
			(start 0.67945 -0.3048)
			(end 0.67945 0.3048)
			(stroke
				(width 0.1)
				(type default)
			)
			(layer "F.Fab")
		)
		(fp_line
			(start 0.12065 -0.3048)
			(end 0.67945 -0.3048)
			(stroke
				(width 0.1)
				(type default)
			)
			(layer "F.Fab")
		)
		(fp_line
			(start 0.12065 -0.2794)
			(end 0.12065 -0.3048)
			(stroke
				(width 0.1)
				(type default)
			)
			(layer "F.Fab")
		)
		(fp_line
			(start -0.12065 -0.2794)
			(end 0.12065 -0.2794)
			(stroke
				(width 0.1)
				(type default)
			)
			(layer "F.Fab")
		)
		(fp_line
			(start 0.120396 0.2794)
			(end -0.12065 0.2794)
			(stroke
				(width 0.1)
				(type default)
			)
			(layer "F.Fab")
		)
		(fp_line
			(start -0.12065 0.2794)
			(end -0.12065 0.3048)
			(stroke
				(width 0.1)
				(type default)
			)
			(layer "F.Fab")
		)
		(fp_line
			(start 0.67945 0.3048)
			(end 0.120396 0.3048)
			(stroke
				(width 0.1)
				(type default)
			)
			(layer "F.Fab")
		)
		(fp_line
			(start 0.120396 0.3048)
			(end 0.120396 0.2794)
			(stroke
				(width 0.1)
				(type default)
			)
			(layer "F.Fab")
		)
		(fp_line
			(start -0.12065 0.3048)
			(end -0.67945 0.3048)
			(stroke
				(width 0.1)
				(type default)
			)
			(layer "F.Fab")
		)
		(fp_line
			(start -0.67945 0.3048)
			(end -0.67945 -0.305054)
			(stroke
				(width 0.1)
				(type default)
			)
			(layer "F.Fab")
		)
		(pad "1" smd circle
			(at -0.40005 0 90)
			(size 0 0)
			(layers "F.Cu" "F.Mask" "F.Paste")
			(net "P3V3_AUX")
		)
		(pad "2" smd circle
			(at 0.40005 0 90)
			(size 0 0)
			(layers "F.Cu" "F.Mask" "F.Paste")
			(net "FM_THERMAL_ALERT_N")
		)
	)
	(footprint ""
		(layer "F.Cu")
		(at 131.579874 -408.517344 -90)
		(property "Reference" "C1523"
			(at 0 0 270)
			(layer "F.SilkS")
			(hide yes)
			(effects
				(font
					(size 1.27 1.27)
				)
			)
		)
		(property "Value" ""
			(at 0 0 270)
			(layer "F.Fab")
			(effects
				(font
					(size 1.27 1.27)
				)
			)
		)
		(duplicate_pad_numbers_are_jumpers no)
		(fp_line
			(start -0.299974 0.150114)
			(end -0.299974 -0.150114)
			(stroke
				(width 0.1)
				(type default)
			)
			(layer "F.Fab")
		)
		(fp_line
			(start 0.299974 0.150114)
			(end -0.299974 0.150114)
			(stroke
				(width 0.1)
				(type default)
			)
			(layer "F.Fab")
		)
		(fp_line
			(start -0.299974 -0.150114)
			(end 0.299974 -0.150114)
			(stroke
				(width 0.1)
				(type default)
			)
			(layer "F.Fab")
		)
		(fp_line
			(start 0.299974 -0.150114)
			(end 0.299974 0.150114)
			(stroke
				(width 0.1)
				(type default)
			)
			(layer "F.Fab")
		)
		(pad "1" smd rect
			(at -0.2667 0 270)
			(size 0.3048 0.381)
			(layers "F.Cu" "F.Mask" "F.Paste")
			(net "P5E_CPU1_PE3_TX_C_DP<12>")
		)
		(pad "2" smd rect
			(at 0.2667 0 270)
			(size 0.3048 0.381)
			(layers "F.Cu" "F.Mask" "F.Paste")
			(net "P5E_CPU1_PE3_TX_DP<12>")
		)
	)
	(footprint ""
		(layer "F.Cu")
		(at 448.799966 -435.59984)
		(property "Reference" "H90"
			(at -3.91922 -2.705608 0)
			(unlocked yes)
			(layer "F.SilkS")
			(effects
				(font
					(size 0.7874 0.5842)
					(thickness 0.1524)
				)
				(justify left)
			)
		)
		(property "Value" ""
			(at 0 0 0)
			(layer "F.Fab")
			(effects
				(font
					(size 1.27 1.27)
				)
			)
		)
		(duplicate_pad_numbers_are_jumpers no)
		(fp_circle
			(center 0 0)
			(end 2.6289 0)
			(stroke
				(width 0.1524)
				(type default)
			)
			(fill no)
			(layer "F.SilkS")
		)
		(fp_circle
			(center 0 0)
			(end 2.6289 0)
			(stroke
				(width 0.1524)
				(type default)
			)
			(fill no)
			(layer "B.SilkS")
		)
		(fp_circle
			(center 0 0)
			(end 2.6289 0)
			(stroke
				(width 0.1)
				(type default)
			)
			(fill no)
			(layer "B.Fab")
		)
		(fp_circle
			(center 0 0)
			(end 2.6289 0)
			(stroke
				(width 0.1)
				(type default)
			)
			(fill no)
			(layer "F.Fab")
		)
		(pad "" np_thru_hole circle
			(at 0 0)
			(size 3.0988 3.0988)
			(drill 3.0988)
			(layers "*.Cu" "*.Mask")
			(clearance 0.254)
			(thermal_gap 0.254)
		)
	)
	(footprint ""
		(layer "F.Cu")
		(at 76.437998 -402.371052 -90)
		(property "Reference" "C729"
			(at 0 0 270)
			(layer "F.SilkS")
			(hide yes)
			(effects
				(font
					(size 1.27 1.27)
				)
			)
		)
		(property "Value" ""
			(at 0 0 270)
			(layer "F.Fab")
			(effects
				(font
					(size 1.27 1.27)
				)
			)
		)
		(duplicate_pad_numbers_are_jumpers no)
		(fp_line
			(start -0.299974 0.150114)
			(end -0.299974 -0.150114)
			(stroke
				(width 0.1)
				(type default)
			)
			(layer "F.Fab")
		)
		(fp_line
			(start 0.299974 0.150114)
			(end -0.299974 0.150114)
			(stroke
				(width 0.1)
				(type default)
			)
			(layer "F.Fab")
		)
		(fp_line
			(start -0.299974 -0.150114)
			(end 0.299974 -0.150114)
			(stroke
				(width 0.1)
				(type default)
			)
			(layer "F.Fab")
		)
		(fp_line
			(start 0.299974 -0.150114)
			(end 0.299974 0.150114)
			(stroke
				(width 0.1)
				(type default)
			)
			(layer "F.Fab")
		)
		(pad "1" smd rect
			(at -0.2667 0 270)
			(size 0.3048 0.381)
			(layers "F.Cu" "F.Mask" "F.Paste")
			(net "P5E_CPU1_PE0_TX_C_DP<6>")
		)
		(pad "2" smd rect
			(at 0.2667 0 270)
			(size 0.3048 0.381)
			(layers "F.Cu" "F.Mask" "F.Paste")
			(net "P5E_CPU1_PE0_TX_DP<6>")
		)
	)
)
